(kicad_pcb
	(version 20260206)
	(generator "pcbnew")
	(generator_version "10.0")
	(general
		(thickness 1.6)
		(legacy_teardrops no)
	)
	(paper "A4")
	(title_block
		(title "v1-tray-backplane — T6M_tray_BP_c_1023_1120.brd")
		(comment 1 "Open CloudServer (Microsoft) / footprints 109-112 of 170")
	)
	(layers
		(0 "F.Cu" signal "TOP")
		(4 "In1.Cu" signal "GND")
		(6 "In2.Cu" signal "IN1")
		(8 "In3.Cu" signal "VCC")
		(10 "In4.Cu" signal "VCC1")
		(12 "In5.Cu" signal "IN2")
		(14 "In6.Cu" signal "GND1")
		(2 "B.Cu" signal "BOTTOM")
		(9 "F.Adhes" user "F.Adhesive")
		(11 "B.Adhes" user "B.Adhesive")
		(13 "F.Paste" user "Package Geometry/Pastemask Top")
		(15 "B.Paste" user "Package Geometry/Pastemask Bottom")
		(5 "F.SilkS" user "Ref Des/Silkscreen Top")
		(7 "B.SilkS" user "Ref Des/Silkscreen Bottom")
		(1 "F.Mask" user "Board Geometry/Soldermask Top")
		(3 "B.Mask" user "Board Geometry/Soldermask Bottom")
		(17 "Dwgs.User" user "User.Drawings")
		(19 "Cmts.User" user "User.Comments")
		(21 "Eco1.User" user "User.Eco1")
		(23 "Eco2.User" user "User.Eco2")
		(25 "Edge.Cuts" user "Board Geometry/Outline")
		(27 "Margin" user)
		(31 "F.CrtYd" user "Package Geometry/Place Bound Top")
		(29 "B.CrtYd" user "Package Geometry/Place Bound Bottom")
		(35 "F.Fab" user "Ref Des/Assembly Top")
		(33 "B.Fab" user "Ref Des/Assembly Bottom")
	)
	(footprint ""
		(layer "F.Cu")
		(at 14.310106 -34.500058)
		(property "Reference" "J20"
			(at 3.20421 4.4323 90)
			(unlocked yes)
			(layer "F.SilkS")
			(effects
				(font
					(size 0.7874 0.5842)
					(thickness 0.1524)
				)
				(justify left)
			)
		)
		(property "Value" ""
			(at 0 0 0)
			(layer "F.Fab")
			(effects
				(font
					(size 1.27 1.27)
				)
			)
		)
		(duplicate_pad_numbers_are_jumpers no)
		(fp_line
			(start -6.299962 10.500106)
			(end -4.899914 10.500106)
			(stroke
				(width 0.1524)
				(type default)
			)
			(layer "F.SilkS")
		)
		(fp_line
			(start -6.299962 13.5001)
			(end -6.299962 10.500106)
			(stroke
				(width 0.1524)
				(type default)
			)
			(layer "F.SilkS")
		)
		(fp_line
			(start -4.899914 -3.325114)
			(end -4.776724 -3.325114)
			(stroke
				(width 0.1524)
				(type default)
			)
			(layer "F.SilkS")
		)
		(fp_line
			(start -4.899914 13.5001)
			(end -6.299962 13.5001)
			(stroke
				(width 0.1524)
				(type default)
			)
			(layer "F.SilkS")
		)
		(fp_line
			(start -4.899914 27.325066)
			(end -4.899914 -3.325114)
			(stroke
				(width 0.1524)
				(type default)
			)
			(layer "F.SilkS")
		)
		(fp_line
			(start -4.776724 27.325066)
			(end -4.878324 27.325066)
			(stroke
				(width 0.1524)
				(type default)
			)
			(layer "F.SilkS")
		)
		(fp_line
			(start -3.100578 -3.325114)
			(end 2.469896 -3.325114)
			(stroke
				(width 0.1524)
				(type default)
			)
			(layer "F.SilkS")
		)
		(fp_line
			(start 2.469896 -3.325114)
			(end 2.469896 27.325066)
			(stroke
				(width 0.1524)
				(type default)
			)
			(layer "F.SilkS")
		)
		(fp_line
			(start 2.469896 27.325066)
			(end -3.100578 27.325066)
			(stroke
				(width 0.1524)
				(type default)
			)
			(layer "F.SilkS")
		)
		(fp_poly
			(pts
				(xy 0.125476 -3.577082) (xy -0.828294 -5.48513) (xy 1.0795 -5.48513)
			)
			(stroke
				(width 0)
				(type default)
			)
			(fill yes)
			(layer "F.SilkS")
		)
		(fp_poly
			(pts
				(xy -6.275578 13.498576) (xy -6.275578 10.501376) (xy -4.903978 10.501376) (xy -4.903978 13.498576)
			)
			(stroke
				(width 0)
				(type default)
			)
			(fill yes)
			(layer "F.SilkS")
		)
		(fp_poly
			(pts
				(xy -3.862324 24.856694) (xy -3.862324 -0.873506) (xy -2.135124 -0.873506) (xy -2.135124 24.856694)
			)
			(stroke
				(width 0)
				(type default)
			)
			(fill no)
			(layer "B.CrtYd")
		)
		(fp_poly
			(pts
				(xy 0.862076 -0.873506) (xy 0.862076 24.856694) (xy -0.85852 24.856694) (xy -0.839724 -0.873506)
			)
			(stroke
				(width 0)
				(type default)
			)
			(fill no)
			(layer "B.CrtYd")
		)
		(fp_poly
			(pts
				(arc
					(start -3.127248 -2.999994)
					(mid -4.752848 -2.999994)
					(end -3.127248 -2.999994)
				)
			)
			(stroke
				(width 0)
				(type default)
			)
			(fill no)
			(layer "B.CrtYd")
		)
		(fp_poly
			(pts
				(arc
					(start -3.127248 26.999946)
					(mid -4.752848 26.999946)
					(end -3.127248 26.999946)
				)
			)
			(stroke
				(width 0)
				(type default)
			)
			(fill no)
			(layer "B.CrtYd")
		)
		(fp_poly
			(pts
				(xy 2.487422 27.337512) (xy -3.201924 27.337512) (xy -3.201924 27.828494) (xy -4.675124 27.828494)
				(xy -4.675124 27.337512) (xy -4.903978 27.337512) (xy -4.903978 13.498576) (xy -6.300978 13.498576)
				(xy -6.300978 10.501376) (xy -4.903978 10.501376) (xy -4.903978 -3.337306) (xy -4.675124 -3.337306)
				(xy -4.675124 -3.819906) (xy -3.201924 -3.819906) (xy -3.201924 -3.337306) (xy 2.487422 -3.337306)
			)
			(stroke
				(width 0)
				(type default)
			)
			(fill no)
			(layer "F.CrtYd")
		)
		(fp_line
			(start -4.899914 -3.325114)
			(end -3.100578 -3.325114)
			(stroke
				(width 0.1)
				(type default)
			)
			(layer "F.Fab")
		)
		(fp_line
			(start -4.899914 27.325066)
			(end -4.899914 -3.325114)
			(stroke
				(width 0.1)
				(type default)
			)
			(layer "F.Fab")
		)
		(fp_line
			(start -3.100578 -3.325114)
			(end 2.469896 -3.325114)
			(stroke
				(width 0.1)
				(type default)
			)
			(layer "F.Fab")
		)
		(fp_line
			(start 2.469896 -3.325114)
			(end 2.469896 27.325066)
			(stroke
				(width 0.1)
				(type default)
			)
			(layer "F.Fab")
		)
		(fp_line
			(start 2.469896 27.325066)
			(end -4.899914 27.325066)
			(stroke
				(width 0.1)
				(type default)
			)
			(layer "F.Fab")
		)
		(fp_poly
			(pts
				(xy -0.026924 -4.059682) (xy -0.980694 -5.96773) (xy 0.9271 -5.96773)
			)
			(stroke
				(width 0)
				(type default)
			)
			(fill yes)
			(layer "F.Fab")
		)
		(fp_text user "13"
			(at -3.902202 -4.907026 0)
			(unlocked yes)
			(layer "F.SilkS")
			(effects
				(font
					(size 0.7874 0.5842)
					(thickness 0.1524)
				)
				(justify left)
			)
		)
		(fp_text user "18"
			(at -0.893826 28.816554 90)
			(unlocked yes)
			(layer "F.SilkS")
			(effects
				(font
					(size 0.7874 0.5842)
					(thickness 0.1524)
				)
				(justify left)
			)
		)
		(fp_text user "9"
			(at 2.981198 23.938738 0)
			(unlocked yes)
			(layer "F.SilkS")
			(effects
				(font
					(size 0.7874 0.5842)
					(thickness 0.1524)
				)
				(justify left)
			)
		)
		(fp_text user "1"
			(at 3.143758 -1.143254 0)
			(unlocked yes)
			(layer "F.SilkS")
			(effects
				(font
					(size 0.7874 0.5842)
					(thickness 0.1524)
				)
				(justify left)
			)
		)
		(fp_text user "13"
			(at -2.988818 -2.346706 90)
			(unlocked yes)
			(layer "B.SilkS")
			(effects
				(font
					(size 0.7874 0.5842)
					(thickness 0.1524)
				)
				(justify left mirror)
			)
		)
		(fp_text user "18"
			(at -2.032254 24.932894 90)
			(unlocked yes)
			(layer "B.SilkS")
			(effects
				(font
					(size 0.7874 0.5842)
					(thickness 0.1524)
				)
				(justify left mirror)
			)
		)
		(fp_text user "1"
			(at -0.093218 -1.953006 90)
			(unlocked yes)
			(layer "B.SilkS")
			(effects
				(font
					(size 0.7874 0.5842)
					(thickness 0.1524)
				)
				(justify left mirror)
			)
		)
		(fp_text user "9"
			(at -0.093218 24.949912 90)
			(unlocked yes)
			(layer "B.SilkS")
			(effects
				(font
					(size 0.7874 0.5842)
					(thickness 0.1524)
				)
				(justify left mirror)
			)
		)
		(fp_text user "13"
			(at -2.988818 -2.346706 90)
			(unlocked yes)
			(layer "B.Fab")
			(effects
				(font
					(size 0.7874 0.5842)
					(thickness 0.000001)
				)
				(justify left mirror)
			)
		)
		(fp_text user "18"
			(at -2.895854 24.780494 90)
			(unlocked yes)
			(layer "B.Fab")
			(effects
				(font
					(size 0.7874 0.5842)
					(thickness 0.000001)
				)
				(justify left mirror)
			)
		)
		(fp_text user "1"
			(at -0.093218 -1.953006 90)
			(unlocked yes)
			(layer "B.Fab")
			(effects
				(font
					(size 0.7874 0.5842)
					(thickness 0.000001)
				)
				(justify left mirror)
			)
		)
		(fp_text user "9"
			(at -0.093218 24.949912 90)
			(unlocked yes)
			(layer "B.Fab")
			(effects
				(font
					(size 0.7874 0.5842)
					(thickness 0.000001)
				)
				(justify left mirror)
			)
		)
		(fp_text user "13"
			(at -3.090418 -3.769106 90)
			(unlocked yes)
			(layer "F.Fab")
			(effects
				(font
					(size 0.7874 0.5842)
					(thickness 0.000001)
				)
				(justify left)
			)
		)
		(fp_text user "18"
			(at -2.895854 29.047694 90)
			(unlocked yes)
			(layer "F.Fab")
			(effects
				(font
					(size 0.7874 0.5842)
					(thickness 0.000001)
				)
				(justify left)
			)
		)
		(fp_text user "9"
			(at -0.178054 28.133294 90)
			(unlocked yes)
			(layer "F.Fab")
			(effects
				(font
					(size 0.7874 0.5842)
					(thickness 0.000001)
				)
				(justify left)
			)
		)
		(fp_text user "1"
			(at -0.118618 -3.578606 90)
			(unlocked yes)
			(layer "F.Fab")
			(effects
				(font
					(size 0.7874 0.5842)
					(thickness 0.000001)
				)
				(justify left)
			)
		)
		(pad "" np_thru_hole circle
			(at -3.940048 -2.999994 90)
			(size 1.0922 1.0922)
			(drill 1.0922)
			(layers "*.Cu" "*.Mask")
			(clearance 0.381)
			(thermal_gap 0.381)
		)
		(pad "" np_thru_hole circle
			(at -3.940048 26.999946 90)
			(size 1.0922 1.0922)
			(drill 1.0922)
			(layers "*.Cu" "*.Mask")
			(clearance 0.381)
			(thermal_gap 0.381)
		)
		(pad "1" thru_hole rect
			(at 0 0 90)
			(size 1.6002 1.6002)
			(drill 1.0922)
			(layers "*.Cu" "*.Mask")
			(remove_unused_layers no)
			(net "GND")
			(clearance 0)
			(padstack
				(mode front_inner_back)
				(layer "Inner"
					(shape circle)
					(size 1.6002 1.6002)
					(clearance 0)
				)
				(layer "B.Cu"
					(shape rect)
					(size 1.6002 1.6002)
					(clearance 0)
				)
			)
		)
		(pad "2" thru_hole circle
			(at 0 2.999994 90)
			(size 1.6002 1.6002)
			(drill 1.0922)
			(layers "*.Cu" "*.Mask")
			(remove_unused_layers no)
			(net "GND")
			(clearance 0)
		)
		(pad "3" thru_hole circle
			(at 0 5.999988 90)
			(size 1.6002 1.6002)
			(drill 1.0922)
			(layers "*.Cu" "*.Mask")
			(remove_unused_layers no)
			(net "GND")
			(clearance 0)
		)
		(pad "4" thru_hole circle
			(at 0 8.999982 90)
			(size 1.6002 1.6002)
			(drill 1.0922)
			(layers "*.Cu" "*.Mask")
			(remove_unused_layers no)
			(net "GND")
			(clearance 0)
		)
		(pad "5" thru_hole circle
			(at 0 11.999976 90)
			(size 1.6002 1.6002)
			(drill 1.0922)
			(layers "*.Cu" "*.Mask")
			(remove_unused_layers no)
			(net "GND")
			(clearance 0)
		)
		(pad "6" thru_hole circle
			(at 0 14.99997 90)
			(size 1.6002 1.6002)
			(drill 1.0922)
			(layers "*.Cu" "*.Mask")
			(remove_unused_layers no)
			(net "GND")
			(clearance 0)
		)
		(pad "7" thru_hole circle
			(at 0 17.999964 90)
			(size 1.6002 1.6002)
			(drill 1.0922)
			(layers "*.Cu" "*.Mask")
			(remove_unused_layers no)
			(net "GND")
			(clearance 0)
		)
		(pad "8" thru_hole circle
			(at 0 20.999958 90)
			(size 1.6002 1.6002)
			(drill 1.0922)
			(layers "*.Cu" "*.Mask")
			(remove_unused_layers no)
			(net "GND")
			(clearance 0)
		)
		(pad "9" thru_hole circle
			(at 0 23.999952 90)
			(size 1.6002 1.6002)
			(drill 1.0922)
			(layers "*.Cu" "*.Mask")
			(remove_unused_layers no)
			(net "GND")
			(clearance 0)
		)
		(pad "10" thru_hole circle
			(at -2.999994 0 90)
			(size 1.6002 1.6002)
			(drill 1.0922)
			(layers "*.Cu" "*.Mask")
			(remove_unused_layers no)
			(net "10")
			(clearance 0)
		)
		(pad "11" thru_hole circle
			(at -2.999994 2.999994 90)
			(size 1.6002 1.6002)
			(drill 1.0922)
			(layers "*.Cu" "*.Mask")
			(remove_unused_layers no)
			(net "P12V")
			(clearance 0)
		)
		(pad "12" thru_hole circle
			(at -2.999994 5.999988 90)
			(size 1.6002 1.6002)
			(drill 1.0922)
			(layers "*.Cu" "*.Mask")
			(remove_unused_layers no)
			(net "P12V")
			(clearance 0)
		)
		(pad "13" thru_hole circle
			(at -2.999994 8.999982 90)
			(size 1.6002 1.6002)
			(drill 1.0922)
			(layers "*.Cu" "*.Mask")
			(remove_unused_layers no)
			(net "P12V")
			(clearance 0)
		)
		(pad "14" thru_hole circle
			(at -2.999994 11.999976 90)
			(size 1.6002 1.6002)
			(drill 1.0922)
			(layers "*.Cu" "*.Mask")
			(remove_unused_layers no)
			(net "P12V")
			(clearance 0)
		)
		(pad "15" thru_hole circle
			(at -2.999994 14.99997 90)
			(size 1.6002 1.6002)
			(drill 1.0922)
			(layers "*.Cu" "*.Mask")
			(remove_unused_layers no)
			(net "P12V")
			(clearance 0)
		)
		(pad "16" thru_hole circle
			(at -2.999994 17.999964 90)
			(size 1.6002 1.6002)
			(drill 1.0922)
			(layers "*.Cu" "*.Mask")
			(remove_unused_layers no)
			(net "P12V")
			(clearance 0)
		)
		(pad "17" thru_hole circle
			(at -2.999994 20.999958 90)
			(size 1.6002 1.6002)
			(drill 1.0922)
			(layers "*.Cu" "*.Mask")
			(remove_unused_layers no)
			(net "P12V")
			(clearance 0)
		)
		(pad "18" thru_hole circle
			(at -2.999994 23.999952 90)
			(size 1.6002 1.6002)
			(drill 1.0922)
			(layers "*.Cu" "*.Mask")
			(remove_unused_layers no)
			(net "P12V")
			(clearance 0)
		)
		(zone
			(layers "F.Cu" "B.Cu" "In1.Cu" "In2.Cu" "In3.Cu" "In4.Cu" "In5.Cu" "In6.Cu")
			(hatch none 0.5)
			(connect_pads
				(clearance 0)
			)
			(min_thickness 0.25)
			(keepout
				(tracks not_allowed)
				(vias allowed)
				(pads allowed)
				(copperpour not_allowed)
				(footprints allowed)
			)
			(placement
				(enabled no)
				(sheetname "")
			)
			(fill
				(thermal_gap 0.5)
				(thermal_bridge_width 0.5)
				(island_removal_mode 0)
			)
			(polygon
				(pts
					(arc
						(start 11.335258 -37.500052)
						(mid 9.404858 -37.500052)
						(end 11.335258 -37.500052)
					)
				)
			)
		)
		(zone
			(layers "F.Cu" "B.Cu" "In1.Cu" "In2.Cu" "In3.Cu" "In4.Cu" "In5.Cu" "In6.Cu")
			(hatch none 0.5)
			(connect_pads
				(clearance 0)
			)
			(min_thickness 0.25)
			(keepout
				(tracks not_allowed)
				(vias allowed)
				(pads allowed)
				(copperpour not_allowed)
				(footprints allowed)
			)
			(placement
				(enabled no)
				(sheetname "")
			)
			(fill
				(thermal_gap 0.5)
				(thermal_bridge_width 0.5)
				(island_removal_mode 0)
			)
			(polygon
				(pts
					(arc
						(start 11.335258 -7.500112)
						(mid 9.404858 -7.500112)
						(end 11.335258 -7.500112)
					)
				)
			)
		)
	)
	(footprint ""
		(layer "F.Cu")
		(at 90.9828 -33.056068)
		(property "Reference" "R79"
			(at -7.0866 2.82067 0)
			(unlocked yes)
			(layer "F.SilkS")
			(effects
				(font
					(size 0.7874 0.5842)
					(thickness 0.1524)
				)
				(justify left)
			)
		)
		(property "Value" ""
			(at 0 0 0)
			(layer "F.Fab")
			(effects
				(font
					(size 1.27 1.27)
				)
			)
		)
		(duplicate_pad_numbers_are_jumpers no)
		(fp_line
			(start -1.905 -0.8636)
			(end 1.905 -0.8636)
			(stroke
				(width 0.1524)
				(type default)
			)
			(layer "F.SilkS")
		)
		(fp_line
			(start -1.905 0.8636)
			(end -1.905 -0.8636)
			(stroke
				(width 0.1524)
				(type default)
			)
			(layer "F.SilkS")
		)
		(fp_line
			(start 1.905 -0.8636)
			(end 1.905 0.8636)
			(stroke
				(width 0.1524)
				(type default)
			)
			(layer "F.SilkS")
		)
		(fp_line
			(start 1.905 0.8636)
			(end -1.905 0.8636)
			(stroke
				(width 0.1524)
				(type default)
			)
			(layer "F.SilkS")
		)
		(fp_poly
			(pts
				(xy 1.524 0.6858) (xy 1.524 -0.6858) (xy 1.524 -0.7366) (xy -1.524 -0.7366) (xy -1.524 -0.6858)
				(xy -1.524 0.6858) (xy -1.524 0.7366) (xy 1.524 0.7366)
			)
			(stroke
				(width 0)
				(type default)
			)
			(fill no)
			(layer "F.CrtYd")
		)
		(pad "1" smd rect
			(at 0.94996 0)
			(size 1.1176 1.3716)
			(layers "F.Cu" "F.Mask" "F.Paste")
			(net "P3V3_BLAD1")
		)
		(pad "2" smd rect
			(at -0.94996 0)
			(size 1.1176 1.3716)
			(layers "F.Cu" "F.Mask" "F.Paste")
			(net "P3V3_10G_2_VCCR")
		)
	)
	(footprint ""
		(layer "F.Cu")
		(at 120.971818 -23.357332)
		(property "Reference" "R59"
			(at -61.6204 5.343652 0)
			(unlocked yes)
			(layer "F.SilkS")
			(effects
				(font
					(size 0.7874 0.5842)
					(thickness 0.1524)
				)
				(justify left)
			)
		)
		(property "Value" ""
			(at 0 0 0)
			(layer "F.Fab")
			(effects
				(font
					(size 1.27 1.27)
				)
			)
		)
		(duplicate_pad_numbers_are_jumpers no)
		(fp_line
			(start -0.7874 -0.4064)
			(end 0.7874 -0.4064)
			(stroke
				(width 0.1524)
				(type default)
			)
			(layer "F.SilkS")
		)
		(fp_line
			(start -0.7874 0.4064)
			(end -0.7874 -0.4064)
			(stroke
				(width 0.1524)
				(type default)
			)
			(layer "F.SilkS")
		)
		(fp_line
			(start 0.7874 -0.4064)
			(end 0.7874 0.4064)
			(stroke
				(width 0.1524)
				(type default)
			)
			(layer "F.SilkS")
		)
		(fp_line
			(start 0.7874 0.4064)
			(end -0.7874 0.4064)
			(stroke
				(width 0.1524)
				(type default)
			)
			(layer "F.SilkS")
		)
		(fp_poly
			(pts
				(xy -0.508 0.2794) (xy -0.508 0.2286) (xy -0.635 0.2286) (xy -0.635 -0.254) (xy -0.5334 -0.254)
				(xy -0.5334 -0.2794) (xy 0.5334 -0.2794) (xy 0.5334 -0.254) (xy 0.635 -0.254) (xy 0.635 0.254) (xy 0.5334 0.254)
				(xy 0.5334 0.2794)
			)
			(stroke
				(width 0)
				(type default)
			)
			(fill no)
			(layer "F.CrtYd")
		)
		(pad "1" smd rect
			(at 0.40005 0)
			(size 0.4572 0.508)
			(layers "F.Cu" "F.Mask" "F.Paste")
			(net "GND")
		)
		(pad "2" smd rect
			(at -0.40005 0)
			(size 0.4572 0.508)
			(layers "F.Cu" "F.Mask" "F.Paste")
			(net "SFP2_PRESENT_N")
		)
	)
	(footprint ""
		(layer "F.Cu")
		(at 30.977332 -16.383 90)
		(property "Reference" "R87"
			(at -3.81 -0.701548 90)
			(unlocked yes)
			(layer "F.SilkS")
			(effects
				(font
					(size 0.7874 0.5842)
					(thickness 0.1524)
				)
				(justify left)
			)
		)
		(property "Value" ""
			(at 0 0 90)
			(layer "F.Fab")
			(effects
				(font
					(size 1.27 1.27)
				)
			)
		)
		(duplicate_pad_numbers_are_jumpers no)
		(fp_line
			(start 0.7874 -0.4064)
			(end 0.7874 0.4064)
			(stroke
				(width 0.1524)
				(type default)
			)
			(layer "F.SilkS")
		)
		(fp_line
			(start -0.7874 -0.4064)
			(end 0.7874 -0.4064)
			(stroke
				(width 0.1524)
				(type default)
			)
			(layer "F.SilkS")
		)
		(fp_line
			(start 0.7874 0.4064)
			(end -0.7874 0.4064)
			(stroke
				(width 0.1524)
				(type default)
			)
			(layer "F.SilkS")
		)
		(fp_line
			(start -0.7874 0.4064)
			(end -0.7874 -0.4064)
			(stroke
				(width 0.1524)
				(type default)
			)
			(layer "F.SilkS")
		)
		(fp_poly
			(pts
				(xy -0.508 0.2794) (xy -0.508 0.2286) (xy -0.635 0.2286) (xy -0.635 -0.254) (xy -0.5334 -0.254)
				(xy -0.5334 -0.2794) (xy 0.5334 -0.2794) (xy 0.5334 -0.254) (xy 0.635 -0.254) (xy 0.635 0.254) (xy 0.5334 0.254)
				(xy 0.5334 0.2794)
			)
			(stroke
				(width 0)
				(type default)
			)
			(fill no)
			(layer "F.CrtYd")
		)
		(pad "1" smd rect
			(at 0.40005 0 90)
			(size 0.4572 0.508)
			(layers "F.Cu" "F.Mask" "F.Paste")
			(net "N39391900")
		)
		(pad "2" smd rect
			(at -0.40005 0 90)
			(size 0.4572 0.508)
			(layers "F.Cu" "F.Mask" "F.Paste")
			(net "GND")
		)
	)
)
